# T6G (Grand Teton) — schematic netlist excerpt (pin names and nets, part order shuffled) for the footprints in the layout excerpt that follows; sources: Cadence DE-HDL packaged netlist, KiCad conversion of 04192023_DAF0TMB3IC0_F0TG_MB_C_brd_V02_OCP.brd

R1616  Q_RES  33 5% CHIP  pkg 0402LF  page 81 : A = FM_ROM_SD_LS_OE ; B = ROM_SD_LS_OE
C591  Q_CAP  10UF 6.3V 20% X6S  pkg C0402  page 290 : A = P1V8_CPU0_RT_1D ; B = GND
C149  Q_CAP  10UF 25V 10% X6S  pkg C0805  page 89 : A = P12V_MEM_CPU0 ; B = GND

(kicad_pcb
	(version 20260206)
	(generator "pcbnew")
	(generator_version "10.0")
	(general
		(thickness 1.6)
		(legacy_teardrops no)
	)
	(paper "A4")
	(title_block
		(title "04192023_DAF0TMB3IC0_F0TG_MB_C_brd_V02_OCP.brd")
		(comment 1 "Grand Teton / footprints 6626-6628 of 8354")
	)
	(layers
		(0 "F.Cu" signal "TOP")
		(4 "In1.Cu" signal "GND")
		(6 "In2.Cu" signal "IN1")
		(8 "In3.Cu" signal "GND1")
		(10 "In4.Cu" signal "IN2")
		(12 "In5.Cu" signal "GND2")
		(14 "In6.Cu" signal "IN3")
		(16 "In7.Cu" signal "GND3")
		(18 "In8.Cu" signal "VCC")
		(20 "In9.Cu" signal "VCC1")
		(22 "In10.Cu" signal "GND4")
		(24 "In11.Cu" signal "IN4")
		(26 "In12.Cu" signal "GND5")
		(28 "In13.Cu" signal "IN5")
		(30 "In14.Cu" signal "GND6")
		(32 "In15.Cu" signal "IN6")
		(34 "In16.Cu" signal "GND7")
		(2 "B.Cu" signal "BOTTOM")
		(9 "F.Adhes" user "F.Adhesive")
		(11 "B.Adhes" user "B.Adhesive")
		(13 "F.Paste" user "Package Geometry/Pastemask Top")
		(15 "B.Paste" user "Package Geometry/Pastemask Bottom")
		(5 "F.SilkS" user "Ref Des/Silkscreen Top")
		(7 "B.SilkS" user "Ref Des/Silkscreen Bottom")
		(1 "F.Mask" user "Board Geometry/Soldermask Top")
		(3 "B.Mask" user "Board Geometry/Soldermask Bottom")
		(17 "Dwgs.User" user "User.Drawings")
		(19 "Cmts.User" user "User.Comments")
		(21 "Eco1.User" user "User.Eco1")
		(23 "Eco2.User" user "User.Eco2")
		(25 "Edge.Cuts" user "Board Geometry/Outline")
		(27 "Margin" user)
		(31 "F.CrtYd" user "Package Geometry/Place Bound Top")
		(29 "B.CrtYd" user "Package Geometry/Place Bound Bottom")
		(35 "F.Fab" user "Ref Des/Assembly Top")
		(33 "B.Fab" user "Ref Des/Assembly Bottom")
	)
	(footprint ""
		(layer "B.Cu")
		(at 360.579924 -395.127988 -90)
		(property "Reference" "C591"
			(at 0 0 90)
			(layer "B.SilkS")
			(hide yes)
			(effects
				(font
					(size 1.27 1.27)
				)
				(justify mirror)
			)
		)
		(property "Value" ""
			(at 0 0 90)
			(layer "B.Fab")
			(effects
				(font
					(size 1.27 1.27)
				)
				(justify mirror)
			)
		)
		(duplicate_pad_numbers_are_jumpers no)
		(fp_line
			(start -0.7874 0.4064)
			(end 0.7874 0.4064)
			(stroke
				(width 0.1524)
				(type default)
			)
			(layer "B.SilkS")
		)
		(fp_line
			(start 0.7874 0.4064)
			(end 0.7874 -0.4064)
			(stroke
				(width 0.1524)
				(type default)
			)
			(layer "B.SilkS")
		)
		(fp_line
			(start -0.7874 -0.4064)
			(end -0.7874 0.4064)
			(stroke
				(width 0.1524)
				(type default)
			)
			(layer "B.SilkS")
		)
		(fp_line
			(start 0.7874 -0.4064)
			(end -0.7874 -0.4064)
			(stroke
				(width 0.1524)
				(type default)
			)
			(layer "B.SilkS")
		)
		(fp_line
			(start -0.67945 0.3048)
			(end -0.120396 0.3048)
			(stroke
				(width 0.1)
				(type default)
			)
			(layer "B.Fab")
		)
		(fp_line
			(start -0.120396 0.3048)
			(end -0.120396 0.2794)
			(stroke
				(width 0.1)
				(type default)
			)
			(layer "B.Fab")
		)
		(fp_line
			(start 0.12065 0.3048)
			(end 0.67945 0.3048)
			(stroke
				(width 0.1)
				(type default)
			)
			(layer "B.Fab")
		)
		(fp_line
			(start 0.67945 0.3048)
			(end 0.67945 -0.305054)
			(stroke
				(width 0.1)
				(type default)
			)
			(layer "B.Fab")
		)
		(fp_line
			(start -0.120396 0.2794)
			(end 0.12065 0.2794)
			(stroke
				(width 0.1)
				(type default)
			)
			(layer "B.Fab")
		)
		(fp_line
			(start 0.12065 0.2794)
			(end 0.12065 0.3048)
			(stroke
				(width 0.1)
				(type default)
			)
			(layer "B.Fab")
		)
		(fp_line
			(start -0.12065 -0.2794)
			(end -0.12065 -0.3048)
			(stroke
				(width 0.1)
				(type default)
			)
			(layer "B.Fab")
		)
		(fp_line
			(start 0.12065 -0.2794)
			(end -0.12065 -0.2794)
			(stroke
				(width 0.1)
				(type default)
			)
			(layer "B.Fab")
		)
		(fp_line
			(start -0.67945 -0.3048)
			(end -0.67945 0.3048)
			(stroke
				(width 0.1)
				(type default)
			)
			(layer "B.Fab")
		)
		(fp_line
			(start -0.12065 -0.3048)
			(end -0.67945 -0.3048)
			(stroke
				(width 0.1)
				(type default)
			)
			(layer "B.Fab")
		)
		(fp_line
			(start 0.12065 -0.305054)
			(end 0.12065 -0.2794)
			(stroke
				(width 0.1)
				(type default)
			)
			(layer "B.Fab")
		)
		(fp_line
			(start 0.67945 -0.305054)
			(end 0.12065 -0.305054)
			(stroke
				(width 0.1)
				(type default)
			)
			(layer "B.Fab")
		)
		(pad "1" smd circle
			(at 0.40005 0 90)
			(size 0 0)
			(layers "B.Cu" "B.Mask" "B.Paste")
			(net "P1V8_CPU0_RT_1D")
		)
		(pad "2" smd circle
			(at -0.40005 0 90)
			(size 0 0)
			(layers "B.Cu" "B.Mask" "B.Paste")
			(net "GND")
		)
	)
	(footprint ""
		(layer "B.Cu")
		(at 195.199 -137.632948 -90)
		(property "Reference" "R1616"
			(at 0 0 90)
			(layer "B.SilkS")
			(hide yes)
			(effects
				(font
					(size 1.27 1.27)
				)
				(justify mirror)
			)
		)
		(property "Value" ""
			(at 0 0 90)
			(layer "B.Fab")
			(effects
				(font
					(size 1.27 1.27)
				)
				(justify mirror)
			)
		)
		(duplicate_pad_numbers_are_jumpers no)
		(fp_line
			(start -0.7874 0.4064)
			(end 0.7874 0.4064)
			(stroke
				(width 0.1524)
				(type default)
			)
			(layer "B.SilkS")
		)
		(fp_line
			(start 0.7874 0.4064)
			(end 0.7874 -0.4064)
			(stroke
				(width 0.1524)
				(type default)
			)
			(layer "B.SilkS")
		)
		(fp_line
			(start -0.7874 -0.4064)
			(end -0.7874 0.4064)
			(stroke
				(width 0.1524)
				(type default)
			)
			(layer "B.SilkS")
		)
		(fp_line
			(start 0.7874 -0.4064)
			(end -0.7874 -0.4064)
			(stroke
				(width 0.1524)
				(type default)
			)
			(layer "B.SilkS")
		)
		(fp_line
			(start -0.67945 0.3048)
			(end -0.120396 0.3048)
			(stroke
				(width 0.1)
				(type default)
			)
			(layer "B.Fab")
		)
		(fp_line
			(start -0.120396 0.3048)
			(end -0.120396 0.2794)
			(stroke
				(width 0.1)
				(type default)
			)
			(layer "B.Fab")
		)
		(fp_line
			(start 0.12065 0.3048)
			(end 0.67945 0.3048)
			(stroke
				(width 0.1)
				(type default)
			)
			(layer "B.Fab")
		)
		(fp_line
			(start 0.67945 0.3048)
			(end 0.67945 -0.305054)
			(stroke
				(width 0.1)
				(type default)
			)
			(layer "B.Fab")
		)
		(fp_line
			(start -0.120396 0.2794)
			(end 0.12065 0.2794)
			(stroke
				(width 0.1)
				(type default)
			)
			(layer "B.Fab")
		)
		(fp_line
			(start 0.12065 0.2794)
			(end 0.12065 0.3048)
			(stroke
				(width 0.1)
				(type default)
			)
			(layer "B.Fab")
		)
		(fp_line
			(start -0.12065 -0.2794)
			(end -0.12065 -0.3048)
			(stroke
				(width 0.1)
				(type default)
			)
			(layer "B.Fab")
		)
		(fp_line
			(start 0.12065 -0.2794)
			(end -0.12065 -0.2794)
			(stroke
				(width 0.1)
				(type default)
			)
			(layer "B.Fab")
		)
		(fp_line
			(start -0.67945 -0.3048)
			(end -0.67945 0.3048)
			(stroke
				(width 0.1)
				(type default)
			)
			(layer "B.Fab")
		)
		(fp_line
			(start -0.12065 -0.3048)
			(end -0.67945 -0.3048)
			(stroke
				(width 0.1)
				(type default)
			)
			(layer "B.Fab")
		)
		(fp_line
			(start 0.12065 -0.305054)
			(end 0.12065 -0.2794)
			(stroke
				(width 0.1)
				(type default)
			)
			(layer "B.Fab")
		)
		(fp_line
			(start 0.67945 -0.305054)
			(end 0.12065 -0.305054)
			(stroke
				(width 0.1)
				(type default)
			)
			(layer "B.Fab")
		)
		(pad "1" smd circle
			(at 0.40005 0 90)
			(size 0 0)
			(layers "B.Cu" "B.Mask" "B.Paste")
			(net "FM_ROM_SD_LS_OE")
		)
		(pad "2" smd circle
			(at -0.40005 0 90)
			(size 0 0)
			(layers "B.Cu" "B.Mask" "B.Paste")
			(net "ROM_SD_LS_OE")
		)
	)
	(footprint ""
		(layer "B.Cu")
		(at 280.636218 -192.660016 180)
		(property "Reference" "C149"
			(at 0 0 0)
			(layer "B.SilkS")
			(hide yes)
			(effects
				(font
					(size 1.27 1.27)
				)
				(justify mirror)
			)
		)
		(property "Value" ""
			(at 0 0 0)
			(layer "B.Fab")
			(effects
				(font
					(size 1.27 1.27)
				)
				(justify mirror)
			)
		)
		(duplicate_pad_numbers_are_jumpers no)
		(fp_line
			(start 1.524 0.762)
			(end 1.524 -0.762)
			(stroke
				(width 0.1524)
				(type default)
			)
			(layer "B.SilkS")
		)
		(fp_line
			(start 1.524 -0.762)
			(end -1.524 -0.762)
			(stroke
				(width 0.1524)
				(type default)
			)
			(layer "B.SilkS")
		)
		(fp_line
			(start -1.524 0.762)
			(end 1.524 0.762)
			(stroke
				(width 0.1524)
				(type default)
			)
			(layer "B.SilkS")
		)
		(fp_line
			(start -1.524 -0.762)
			(end -1.524 0.762)
			(stroke
				(width 0.1524)
				(type default)
			)
			(layer "B.SilkS")
		)
		(fp_line
			(start 1.1049 0.724916)
			(end -1.1049 0.724916)
			(stroke
				(width 0.1)
				(type default)
			)
			(layer "B.Fab")
		)
		(fp_line
			(start 1.1049 -0.724916)
			(end 1.1049 0.724916)
			(stroke
				(width 0.1)
				(type default)
			)
			(layer "B.Fab")
		)
		(fp_line
			(start -1.1049 0.724916)
			(end -1.1049 -0.724916)
			(stroke
				(width 0.1)
				(type default)
			)
			(layer "B.Fab")
		)
		(fp_line
			(start -1.1049 -0.724916)
			(end 1.1049 -0.724916)
			(stroke
				(width 0.1)
				(type default)
			)
			(layer "B.Fab")
		)
		(pad "1" smd rect
			(at 0.889 0 180)
			(size 1.016 1.27)
			(layers "B.Cu" "B.Mask" "B.Paste")
			(net "P12V_MEM_CPU0")
		)
		(pad "2" smd rect
			(at -0.889 0 180)
			(size 1.016 1.27)
			(layers "B.Cu" "B.Mask" "B.Paste")
			(net "GND")
		)
	)
)
